# T6G (Grand Teton) — schematic parts with pin connectivity, parts 4632–4659 of 8303; source: Cadence DE-HDL packaged netlist (pstxprt.dat, pstxnet.dat, pstchip.dat)

PU299  RS31312R  IC  pkg QFN22_TH_3X5  page 152
  1  EN  IN  = P12V_SCM_EN_R2
  2  LOADEN  IN  = GND
  3  ENTM  IN  = GND
  4  TIMER  IN  = P12V_SCM_TIMER
  5  ISET  IN  = P12V_SCM_ISET
  6  SS  IN  = P12V_SCM_SS
  7  GND  POWER  = GND
  8  IMON  OUT  = P12V_SCM_IMON
  9  FLTB  OUT  = P12V_SCM_FLTB_N
  10  PG  OUT  = HP_LVC3_SCM_HSC_PWRGD_R
  11  OV  IN  = P12V_SCM_OV_FB
  12  AVIN  IN  = P12V_SCM_AVIN_PD
  13  VOUT_13  OUT  = P12V_SCM_R
  14  VOUT_14  OUT  = P12V_SCM_R
  15  VOUT_15  OUT  = P12V_SCM_R
  16  VOUT_16  OUT  = P12V_SCM_R
  17  VOUT_17  OUT  = P12V_SCM_R
  18  VOUT_18  OUT  = P12V_SCM_R
  19  VOUT_19  OUT  = P12V_SCM_R
  20  VOUT_20  OUT  = P12V_SCM_R
  21_22  VIN_21_22  IN  = P12V_AUX
  23  VIN_23  IN  = P12V_AUX
  24  VIN_24  IN  = P12V_AUX
  25  VIN_25  IN  = P12V_AUX
  26  VIN_26  IN  = P12V_AUX

PU300  MAX15090BEWIT  MAX15090BEWI+T IC  pkg BGA28_0-5_3-525X2-065  page 152
  A1  ISENSE  OUT  = P12V_SCM_SENSE
  A2  VCC  POWER  = P12V_SCM_VCC
  A3  IN_A3  IN  = P12V_AUX
  A4  OUT_A4  OUT  = P12V_SCM_R
  A5  IN_A5  IN  = P12V_AUX
  A6  GATE  BI  = P12V_SCM_GATE
  A7  CDLY  IN  = GND
  B1  CB  BI  = P12V_SCM_CB
  B2  GND_B2  POWER  = GND
  B3  IN_B3  IN  = P12V_AUX
  B4  OUT_B4  OUT  = P12V_SCM_R
  B5  IN_B5  IN  = P12V_AUX
  B6  OUT_B6  OUT  = P12V_SCM_R
  B7  \en#\  IN  = GND
  C1  GND_C1  POWER  = GND
  C2  GND_C2  POWER  = GND
  C3  IN_C3  IN  = P12V_AUX
  C4  OUT_C4  OUT  = P12V_SCM_R
  C5  IN_C5  IN  = P12V_AUX
  C6  OUT_C6  OUT  = P12V_SCM_R
  C7  \fault#\  OUT  = P12V_SCM_FAULT_N
  D1  REG  OUT  = P12V_SCM_REG
  D2  UV  IN  = P12V_SCM_UV
  D3  OV  IN  = P12V_SCM_OV
  D4  OUT_D4  OUT  = P12V_SCM_R
  D5  IN_D5  IN  = P12V_AUX
  D6  OUT_D6  OUT  = P12V_SCM_R
  D7  PG  OUT  = P12V_SCM_PWRGD

PU6000  MPQ8626GDZ  MPQ8626GD-Z IC  pkg QFN14_0-5_3X2XA  page 269
  1  PGND1  POWER  = GND
  2  SW1  OUT  = SW_P1V8_AUX_PH
  3  VIN  IN  = SW_P12V_AUX_P1V8_AUX_FLT
  4  CS  IN  = P1V8_AUX_CS
  5  EN  IN  = P1V8_AUX_ENABLE
  6  FB  IN  = P1V8_AUX_FB
  7  AGND  POWER  = GND
  8  TRK_REF  IN  = P1V8_AUX_REF
  9  PGOOD  OUT  = PWRGD_P1V8_AUX
  10  BST  IN  = SW_P1V8_AUX_BT
  11  SW2  OUT  = SW_P1V8_AUX_PH
  12  MODE  IN  = P1V8_AUX_MODE
  13  VCC  OUT  = P1V8_AUX_VCC
  14  PGND2  POWER  = GND

PU6001  MPQ8626GDZ  MPQ8626GD-Z IC  pkg QFN14_0-5_3X2XA  page 270
  1  PGND1  POWER  = GND
  2  SW1  OUT  = SW_P1V2_AUX_PH
  3  VIN  IN  = SW_P12V_AUX_P1V2_AUX_FLT
  4  CS  IN  = P1V2_AUX_CS
  5  EN  IN  = P1V2_AUX_ENABLE
  6  FB  IN  = P1V2_AUX_FB
  7  AGND  POWER  = GND
  8  TRK_REF  IN  = P1V2_AUX_REF
  9  PGOOD  OUT  = PWRGD_P1V2_AUX
  10  BST  IN  = SW_P1V2_AUX_BT
  11  SW2  OUT  = SW_P1V2_AUX_PH
  12  MODE  IN  = P1V2_AUX_MODE
  13  VCC  OUT  = P1V2_AUX_VCC
  14  PGND2  POWER  = GND

PU6500  MPQ8633BGLEC838Z  MPQ8633BGLE-C838-Z IC  pkg QFN14_4X3  page 360
  1  BST  IN  = SW_P1V8_RETIMER_CPU0_BST
  2  AGND  POWER  = GND
  3  CS  IN  = P1V8_RETIMER_CPU0_CS
  4  MODE  IN  = P1V8_RETIMER_CPU0_MODE
  5  TRK_REF  IN  = P1V8_RETIMER_CPU0_REF
  6  RGND  POWER  = GND
  7  FB  IN  = P1V8_RETIMER_CPU0_FB
  8  EN  IN  = P1V8_RETIMER_CPU0_EN
  9  PGOOD  OUT  = PWRGD_P1V8_RETIMER_CPU0
  10  VIN1  IN  = SW_P12V_AUX_P1V8_RETIMER_CPU0_FLT
  11_18  PGND  POWER  = GND
  19  VCC  IN  = P1V8_RETIMER_CPU0_VCC
  20  SW  OUT  = SW_P1V8_RETIMER_CPU0_SW
  21  VIN2  IN  = SW_P12V_AUX_P1V8_RETIMER_CPU0_FLT

PU6501  MPQ8633BGLEC838Z  MPQ8633BGLE-C838-Z IC  pkg QFN14_4X3  page 361
  1  BST  IN  = SW_P1V8_RETIMER_CPU1_BST
  2  AGND  POWER  = GND
  3  CS  IN  = P1V8_RETIMER_CPU1_CS
  4  MODE  IN  = P1V8_RETIMER_CPU1_MODE
  5  TRK_REF  IN  = P1V8_RETIMER_CPU1_REF
  6  RGND  POWER  = GND
  7  FB  IN  = P1V8_RETIMER_CPU1_FB
  8  EN  IN  = P1V8_RETIMER_CPU1_EN
  9  PGOOD  OUT  = PWRGD_P1V8_RETIMER_CPU1
  10  VIN1  IN  = SW_P12V_AUX_P1V8_RETIMER_CPU1_FLT
  11_18  PGND  POWER  = GND
  19  VCC  IN  = P1V8_RETIMER_CPU1_VCC
  20  SW  OUT  = SW_P1V8_RETIMER_CPU1_SW
  21  VIN2  IN  = SW_P12V_AUX_P1V8_RETIMER_CPU1_FLT

PU6502  ISL69260IRAZT  ISL69260IRAZ-T IC  pkg QFN40_TH_0-4_5X5XE  page 362
  1  PWM0  OUT  = NC_P0V9_RETIMER_CPU0_PWM8
  2  PWM1  OUT  = NC_P0V9_RETIMER_CPU0_PWM7
  3  PWM2  OUT  = NC_P0V9_RETIMER_CPU0_PWM6
  4  PWM3  OUT  = NC_P0V9_RETIMER_CPU0_PWM5
  5  PWM4  OUT  = NC_P0V9_RETIMER_CPU0_PWM4
  6  PWM5  OUT  = NC_P0V9_RETIMER_CPU0_PWM3
  7  PWM6  OUT  = P0V9_RETIMER_CPU0_PWM2
  8  PWM7  OUT  = P0V9_RETIMER_CPU0_PWM1
  9  PMSDA  BI  = P0V9_RETIMER_CPU0_PMSDA_R
  10  PMSCL  IN  = P0V9_RETIMER_CPU0_PMSCL_R
  11  \npmalert#\  OUT  = TP_P0V9_RETIMER_CPU0_PMALERT
  12  PG0  OUT  = PWRGD_P0V9_RETIMER_CPU0_R
  13  EN0  IN  = P0V9_RETIMER_CPU0_EN0_R
  14  \nvrhot#\  OUT  = P0V9_RETIMER_CPU0_VRHOT
  15  \npinalert#||npsyscrit#\  OUT  = P0V9_RETIMER_CPU0_INALERT
  16  PG1  OUT  = NC_P0V9_RETIMER_CPU0_PG1
  17  SVCLK  IN  = P0V9_RETIMER_CPU0_SVID_CLK
  18  SVDATA  BI  = P0V9_RETIMER_CPU0_SVID_SDA
  19  \nsvalert#\  OUT  = TP_P0V9_RETIMER_CPU0_SVID_ALERT_N
  20  EN1  IN  = P0V9_RETIMER_CPU0_EN1_R
  21  VSEN0  IN  = P0V9_RETIMER_CPU0_SENSE_R_P
  22  RGND0  IN  = P0V9_RETIMER_CPU0_SENSE_SH_N
  23  CS7  IN  = P0V9_RETIMER_CPU0_IMON1
  24  CS6  IN  = P0V9_RETIMER_CPU0_IMON2
  25  CS5  IN  = NC_P0V9_RETIMER_CPU0_IMON3
  26  CS4  IN  = NC_P0V9_RETIMER_CPU0_IMON4
  27  CS3  IN  = NC_P0V9_RETIMER_CPU0_IMON5
  28  CS2  IN  = NC_P0V9_RETIMER_CPU0_IMON6
  29  CS1  IN  = NC_P0V9_RETIMER_CPU0_IMON7
  30  CS0  IN  = NC_P0V9_RETIMER_CPU0_IMON8
  31  RGND1  IN  = GND
  32  VSEN1  IN  = GND
  33  CFP  OUT  = P0V9_RETIMER_CPU0_CFP
  34  ADDR_CFG  IN  = P0V9_RETIMER_CPU0_ADDR
  35  TEMP0  IN  = P0V9_RETIMER_CPU0_TEMP0
  36  \temp1||isys\  IN  = P0V9_RETIMER_CPU0_TEMP1_R
  37  \vmon||iinsen||vsys||isys\  IN  = P0V9_RETIMER_CPU0_VMON
  38  \vinsen||vsys\  IN  = P0V9_RETIMER_CPU0_VINSEN
  39  VCC  POWER  = P0V9_RETIMER_CPU0_VCC
  40  VCCS  POWER  = PV09_RETIMER_CPU0_VCCS
  TH  TH_GND  POWER  = GND

PU6503  ISL99390FRZTR5935  ISL99390FRZ-TR5935 IC  pkg QFN21_6X5XB  page 363
  1  VOS  IN  = P0V9_RETIMER_CPU0_VOS1
  2  AGND  POWER  = GND
  3  VCC  POWER  = P0V9_RETIMER_CPU0_VCC1
  4  PVCC  POWER  = P0V9_RETIMER_CPU0_PVCC
  5  PGND1  POWER  = GND
  6  GL1  OUT  = NC_PV09_RETIMER_CPU0_GL1_1
  7_9-20_24  PGND2  POWER  = GND
  10_19  SW  OUT  = SW_P0V9_RETIMER_CPU0_SW1
  25_29  VIN1  IN  = SW_P12V_AUX_P0V9_RETIMER_CPU0_FLT
  30  VIN2  IN  = SW_P12V_AUX_P0V9_RETIMER_CPU0_FLT
  31  DNC  TRI  = NC_PV09_RETIMER_CPU0_DNC1
  32  PHASE  POWER  = SW_P0V9_RETIMER_CPU0_PH1
  33  BOOT  POWER  = SW_P0V9_RETIMER_CPU0_BOOT1
  34  PWM  IN  = P0V9_RETIMER_CPU0_PWM1
  35  EN  IN  = P0V9_RETIMER_CPU0_VCC1
  36  TOUT_FLT  OUT  = P0V9_RETIMER_CPU0_TEMP0
  37  LSET  OUT  = P0V9_RETIMER_CPU0_LSET1
  38  IOUT  OUT  = P0V9_RETIMER_CPU0_IMON1
  39  REFIN  IN  = PV09_RETIMER_CPU0_VCCS
  40  PGND3  POWER  = GND
  41  GL2  OUT  = NC_PV09_RETIMER_CPU0_GL2_1

PU6504  ISL99390FRZTR5935  ISL99390FRZ-TR5935 IC  pkg QFN21_6X5XB  page 363
  1  VOS  IN  = P0V9_RETIMER_CPU0_VOS2
  2  AGND  POWER  = GND
  3  VCC  POWER  = P0V9_RETIMER_CPU0_VCC2
  4  PVCC  POWER  = P0V9_RETIMER_CPU0_PVCC
  5  PGND1  POWER  = GND
  6  GL1  OUT  = NC_PV09_RETIMER_CPU0_GL1_2
  7_9-20_24  PGND2  POWER  = GND
  10_19  SW  OUT  = SW_P0V9_RETIMER_CPU0_SW2
  25_29  VIN1  IN  = SW_P12V_AUX_P0V9_RETIMER_CPU0_FLT
  30  VIN2  IN  = SW_P12V_AUX_P0V9_RETIMER_CPU0_FLT
  31  DNC  TRI  = NC_PV09_RETIMER_CPU0_DNC2
  32  PHASE  POWER  = SW_P0V9_RETIMER_CPU0_PH2
  33  BOOT  POWER  = SW_P0V9_RETIMER_CPU0_BOOT2
  34  PWM  IN  = P0V9_RETIMER_CPU0_PWM2
  35  EN  IN  = P0V9_RETIMER_CPU0_VCC2
  36  TOUT_FLT  OUT  = P0V9_RETIMER_CPU0_TEMP0
  37  LSET  OUT  = P0V9_RETIMER_CPU0_LSET2
  38  IOUT  OUT  = P0V9_RETIMER_CPU0_IMON2
  39  REFIN  IN  = PV09_RETIMER_CPU0_VCCS
  40  PGND3  POWER  = GND
  41  GL2  OUT  = NC_PV09_RETIMER_CPU0_GL2_2

PU6510  ISL69260IRAZT  ISL69260IRAZ-T IC  pkg QFN40_TH_0-4_5X5XE  page 364
  1  PWM0  OUT  = NC_P0V9_RETIMER_CPU1_PWM8
  2  PWM1  OUT  = NC_P0V9_RETIMER_CPU1_PWM7
  3  PWM2  OUT  = NC_P0V9_RETIMER_CPU1_PWM6
  4  PWM3  OUT  = NC_P0V9_RETIMER_CPU1_PWM5
  5  PWM4  OUT  = NC_P0V9_RETIMER_CPU1_PWM4
  6  PWM5  OUT  = NC_P0V9_RETIMER_CPU1_PWM3
  7  PWM6  OUT  = P0V9_RETIMER_CPU1_PWM2
  8  PWM7  OUT  = P0V9_RETIMER_CPU1_PWM1
  9  PMSDA  BI  = P0V9_RETIMER_CPU1_PMSDA_R
  10  PMSCL  IN  = P0V9_RETIMER_CPU1_PMSCL_R
  11  \npmalert#\  OUT  = TP_P0V9_RETIMER_CPU1_PMALERT
  12  PG0  OUT  = PWRGD_P0V9_RETIMER_CPU1_R
  13  EN0  IN  = P0V9_RETIMER_CPU1_EN0_R
  14  \nvrhot#\  OUT  = P0V9_RETIMER_CPU1_VRHOT
  15  \npinalert#||npsyscrit#\  OUT  = P0V9_RETIMER_CPU1_INALERT
  16  PG1  OUT  = NC_P0V9_RETIMER_CPU1_PG1
  17  SVCLK  IN  = P0V9_RETIMER_CPU1_SVID_CLK
  18  SVDATA  BI  = P0V9_RETIMER_CPU1_SVID_SDA
  19  \nsvalert#\  OUT  = TP_P0V9_RETIMER_CPU1_SVID_ALERT_N
  20  EN1  IN  = P0V9_RETIMER_CPU1_EN1_R
  21  VSEN0  IN  = P0V9_RETIMER_CPU1_SENSE_R_P
  22  RGND0  IN  = P0V9_RETIMER_CPU1_SENSE_SH_N
  23  CS7  IN  = P0V9_RETIMER_CPU1_IMON1
  24  CS6  IN  = P0V9_RETIMER_CPU1_IMON2
  25  CS5  IN  = NC_P0V9_RETIMER_CPU1_IMON3
  26  CS4  IN  = NC_P0V9_RETIMER_CPU1_IMON4
  27  CS3  IN  = NC_P0V9_RETIMER_CPU1_IMON5
  28  CS2  IN  = NC_P0V9_RETIMER_CPU1_IMON6
  29  CS1  IN  = NC_P0V9_RETIMER_CPU1_IMON7
  30  CS0  IN  = NC_P0V9_RETIMER_CPU1_IMON8
  31  RGND1  IN  = GND
  32  VSEN1  IN  = GND
  33  CFP  OUT  = P0V9_RETIMER_CPU1_CFP
  34  ADDR_CFG  IN  = P0V9_RETIMER_CPU1_ADDR
  35  TEMP0  IN  = P0V9_RETIMER_CPU1_TEMP0
  36  \temp1||isys\  IN  = P0V9_RETIMER_CPU1_TEMP1_R
  37  \vmon||iinsen||vsys||isys\  IN  = P0V9_RETIMER_CPU1_VMON
  38  \vinsen||vsys\  IN  = P0V9_RETIMER_CPU1_VINSEN
  39  VCC  POWER  = P0V9_RETIMER_CPU1_VCC
  40  VCCS  POWER  = PV09_RETIMER_CPU1_VCCS
  TH  TH_GND  POWER  = GND

PU6511  ISL99390FRZTR5935  ISL99390FRZ-TR5935 IC  pkg QFN21_6X5XB  page 365
  1  VOS  IN  = P0V9_RETIMER_CPU1_VOS1
  2  AGND  POWER  = GND
  3  VCC  POWER  = P0V9_RETIMER_CPU1_VCC1
  4  PVCC  POWER  = P0V9_RETIMER_CPU1_PVCC
  5  PGND1  POWER  = GND
  6  GL1  OUT  = NC_PV09_RETIMER_CPU1_GL1_1
  7_9-20_24  PGND2  POWER  = GND
  10_19  SW  OUT  = SW_P0V9_RETIMER_CPU1_SW1
  25_29  VIN1  IN  = SW_P12V_AUX_P0V9_RETIMER_CPU1_FLT
  30  VIN2  IN  = SW_P12V_AUX_P0V9_RETIMER_CPU1_FLT
  31  DNC  TRI  = NC_PV09_RETIMER_CPU1_DNC1
  32  PHASE  POWER  = SW_P0V9_RETIMER_CPU1_PH1
  33  BOOT  POWER  = SW_P0V9_RETIMER_CPU1_BOOT1
  34  PWM  IN  = P0V9_RETIMER_CPU1_PWM1
  35  EN  IN  = P0V9_RETIMER_CPU1_VCC1
  36  TOUT_FLT  OUT  = P0V9_RETIMER_CPU1_TEMP0
  37  LSET  OUT  = P0V9_RETIMER_CPU1_LSET1
  38  IOUT  OUT  = P0V9_RETIMER_CPU1_IMON1
  39  REFIN  IN  = PV09_RETIMER_CPU1_VCCS
  40  PGND3  POWER  = GND
  41  GL2  OUT  = NC_PV09_RETIMER_CPU1_GL2_1

PU6512  ISL99390FRZTR5935  ISL99390FRZ-TR5935 IC  pkg QFN21_6X5XB  page 365
  1  VOS  IN  = P0V9_RETIMER_CPU1_VOS2
  2  AGND  POWER  = GND
  3  VCC  POWER  = P0V9_RETIMER_CPU1_VCC2
  4  PVCC  POWER  = P0V9_RETIMER_CPU1_PVCC
  5  PGND1  POWER  = GND
  6  GL1  OUT  = NC_PV09_RETIMER_CPU1_GL1_2
  7_9-20_24  PGND2  POWER  = GND
  10_19  SW  OUT  = SW_P0V9_RETIMER_CPU1_SW2
  25_29  VIN1  IN  = SW_P12V_AUX_P0V9_RETIMER_CPU1_FLT
  30  VIN2  IN  = SW_P12V_AUX_P0V9_RETIMER_CPU1_FLT
  31  DNC  TRI  = NC_PV09_RETIMER_CPU1_DNC2
  32  PHASE  POWER  = SW_P0V9_RETIMER_CPU1_PH2
  33  BOOT  POWER  = SW_P0V9_RETIMER_CPU1_BOOT2
  34  PWM  IN  = P0V9_RETIMER_CPU1_PWM2
  35  EN  IN  = P0V9_RETIMER_CPU1_VCC2
  36  TOUT_FLT  OUT  = P0V9_RETIMER_CPU1_TEMP0
  37  LSET  OUT  = P0V9_RETIMER_CPU1_LSET2
  38  IOUT  OUT  = P0V9_RETIMER_CPU1_IMON2
  39  REFIN  IN  = PV09_RETIMER_CPU1_VCCS
  40  PGND3  POWER  = GND
  41  GL2  OUT  = NC_PV09_RETIMER_CPU1_GL2_2

Q1  MOSFET_NCH_DUAL  PJT138K IC  pkg SOT363XD  page 188
  1  S1  BI  = GND
  2  G1  BI  = PWRGD_P5V_R1
  3  D2  BI  = PWRGD_P5V_R2
  4  S2  BI  = GND
  5  G2  BI  = PWRGD_P5V_N
  6  D1  BI  = PWRGD_P5V_R_N

Q2  MOSFET_DUAL_6P  2N7002KDW IC  pkg SOT363XD  page 166
  1  S1  BI  = GND
  2  G1  BI  = BOOT_RDY_BUF_LED
  3  D2  BI  = BOOT_RDY_LED_N
  4  S2  BI  = GND
  5  G2  BI  = BOOT_RDY_LED
  6  D1  BI  = BOOT_RDY_LED

Q3  MOSFET_NCH_DUAL  PJT138K IC  pkg SOT363XD  page 188
  1  S1  BI  = GND
  2  G1  BI  = SW_P3V3_EN_R
  3  D2  BI  = SW_P3V3_EN_ISO
  4  S2  BI  = GND
  5  G2  BI  = SW_P3V3_EN_N
  6  D1  BI  = SW_P3V3_EN_N

Q4  MOSFET_DUAL_6P  2N7002KDW IC  pkg SOT363XD  page 155
  1  S1  BI  = GND
  2  G1  BI  = IRQ_LVC3_WAKE_N
  3  D2  BI  = IRQ_WAKE_R_N
  4  S2  BI  = GND
  5  G2  BI  = IRQ_LVC3_WAKE
  6  D1  BI  = IRQ_LVC3_WAKE

Q8  MOSFET_DUAL_6P  2N7002KDW IC  pkg SOT363XD  page 187
  1  S1  BI  = GND
  2  G1  BI  = CLR_CMOS
  3  D2  BI  = BAT_LDO_EN
  4  S2  BI  = GND
  5  G2  BI  = CLR_CMOS
  6  D1  BI  = CLR_CMOS_N

Q11  MOSFET_DUAL_6P  2N7002KDW IC  pkg SOT363XD  page 166
  1  S1  BI  = GND
  2  G1  BI  = FM_SMERR_BUF_R_LED_N
  3  D2  BI  = SMERR_LED_N
  4  S2  BI  = GND
  5  G2  BI  = SMERR_LED
  6  D1  BI  = SMERR_LED

Q12  MOSFET_N_GSD  NX138BK IC  pkg SOT23_GDSXE  page 166
  D  DRAIN  BI  = P12V_ALL_PWROK_N
  G  GATE  IN  = P12V_ALL_PWROK
  S  SOURCE  BI  = GND

Q18  BSS138DW7F  BSS138DW-7-F IC  pkg SOT363A  page 259
  1  S1  BI  = GND
  2  G1  BI  = PWRGD_P12V_MEM_CPU0_EN
  3  D2  BI  = PWRGD_P12V_MEM_CPU0
  4  S2  BI  = GND
  5  G2  BI  = PWRGD_P12V_MEM_CPU0_EN_N
  6  D1  BI  = PWRGD_P12V_MEM_CPU0_EN_N

Q19  BSS138DW7F  BSS138DW-7-F IC  pkg SOT363A  page 259
  1  S1  BI  = GND
  2  G1  BI  = PWRGD_P12V_MEM_CPU1_EN
  3  D2  BI  = PWRGD_P12V_MEM_CPU1
  4  S2  BI  = GND
  5  G2  BI  = PWRGD_P12V_MEM_CPU1_EN_N
  6  D1  BI  = PWRGD_P12V_MEM_CPU1_EN_N

Q27  BSS138DW7F  BSS138DW-7-F IC  pkg SOT363A  page 188
  1  S1  BI  = GND
  2  G1  BI  = PWRGD_P3V3_EN
  3  D2  BI  = PWRGD_P3V3_R1
  4  S2  BI  = GND
  5  G2  BI  = PWRGD_P3V3_EN_N
  6  D1  BI  = PWRGD_P3V3_EN_N

Q28  MOSFET_DUAL_6P  2N7002KDW IC  pkg SOT363XD  page 85
  1  S1  BI  = GND
  2  G1  BI  = BMC_FPGA_LED1
  3  D2  BI  = BMC_FPGA_LED2_N
  4  S2  BI  = GND
  5  G2  BI  = BMC_FPGA_LED2
  6  D1  BI  = BMC_FPGA_LED1_N

Q29  MOSFET_N_GSD  NX138BK IC  pkg SOT23_GDSXE  page 165
  D  DRAIN  BI  = LED_BIOS_DBG_MODE
  G  GATE  IN  = LED_BIOS_DBG_MODE_N
  S  SOURCE  BI  = GND

Q30  MOSFET_N_GSD  NX138BK IC  pkg SOT23_GDSXE  page 165
  D  DRAIN  BI  = LED_BIOS_DBG_MODE_N
  G  GATE  IN  = BIOS_DEBUG_MODE
  S  SOURCE  BI  = GND

Q37  MOSFET_NCH_DUAL  PJT138K IC  pkg SOT363XD  page 188
  1  S1  BI  = GND
  2  G1  BI  = VR_P5V_EN
  3  D2  BI  = VR_P5V_EN_D_R1
  4  S2  BI  = GND
  5  G2  BI  = VR_P5V_EN_N
  6  D1  BI  = VR_P5V_EN_N

Q39  MOSFET_NCH_GDS_ESD_PROTECTED  2N7002K IC  pkg SOT23_GDSXC  page 152
  D  D  BI  = P12V_SCM_EN
  G  G  IN  = FM_SCM_PRSNT1_R_N
  S  S  BI  = GND

Q50  MOSFET_NCH_DUAL  PJT138K IC  pkg SOT363XD  page 85
  1  S1  BI  = GND
  2  G1  BI  = PWRGD_P5V_AUX
  3  D2  BI  = PWRGD_P5V_AUX_R2
  4  S2  BI  = GND
  5  G2  BI  = PWRGD_P5V_AUX_R1
  6  D1  BI  = PWRGD_P5V_AUX_R1
